(kicad_pcb
	(version 20260206)
	(generator "pcbnew")
	(generator_version "10.0")
	(general
		(thickness 1.6)
		(legacy_teardrops no)
	)
	(paper "A4")
	(title_block
		(title "pdpb — Lightning_PDPB_BRD.brd")
		(comment 1 "Lightning (Wiwynn / Facebook NVMe JBOF) / footprints 211-217 of 1140")
	)
	(layers
		(0 "F.Cu" signal "TOP")
		(4 "In1.Cu" signal "L2GND")
		(6 "In2.Cu" signal "L3")
		(8 "In3.Cu" signal "L4VCC")
		(10 "In4.Cu" signal "L5VCC")
		(12 "In5.Cu" signal "L6")
		(14 "In6.Cu" signal "L7GND")
		(2 "B.Cu" signal "BOTTOM")
		(9 "F.Adhes" user "F.Adhesive")
		(11 "B.Adhes" user "B.Adhesive")
		(13 "F.Paste" user "Package Geometry/Pastemask Top")
		(15 "B.Paste" user "Package Geometry/Pastemask Bottom")
		(5 "F.SilkS" user "Ref Des/Silkscreen Top")
		(7 "B.SilkS" user "Ref Des/Silkscreen Bottom")
		(1 "F.Mask" user "Board Geometry/Soldermask Top")
		(3 "B.Mask" user "Board Geometry/Soldermask Bottom")
		(17 "Dwgs.User" user "User.Drawings")
		(19 "Cmts.User" user "User.Comments")
		(21 "Eco1.User" user "User.Eco1")
		(23 "Eco2.User" user "User.Eco2")
		(25 "Edge.Cuts" user "Board Geometry/Outline")
		(27 "Margin" user)
		(31 "F.CrtYd" user "Package Geometry/Place Bound Top")
		(29 "B.CrtYd" user "Package Geometry/Place Bound Bottom")
		(35 "F.Fab" user "Ref Des/Assembly Top")
		(33 "B.Fab" user "Ref Des/Assembly Bottom")
	)
	(footprint ""
		(layer "F.Cu")
		(at 34.671 -38.735)
		(property "Reference" "Q75"
			(at 0 0 0)
			(layer "F.SilkS")
			(hide yes)
			(effects
				(font
					(size 1.27 1.27)
				)
			)
		)
		(property "Value" "2N7002A-7-GP"
			(at 0.127 -8.9662 0)
			(unlocked yes)
			(layer "F.Fab")
			(hide yes)
			(effects
				(font
					(size 1.016 1.016)
					(thickness 0.1524)
				)
			)
		)
		(property "Device Type" "SOT23DGS2D4H48"
			(at 0.127 -10.4902 0)
			(unlocked yes)
			(layer "F.Fab")
			(hide yes)
			(effects
				(font
					(size 1.016 1.016)
					(thickness 0.1524)
				)
			)
		)
		(duplicate_pad_numbers_are_jumpers no)
		(fp_line
			(start -1.651 -1.778)
			(end -1.651 1.778)
			(stroke
				(width 0.1524)
				(type default)
			)
			(layer "F.SilkS")
		)
		(fp_line
			(start -1.651 1.778)
			(end 1.651 1.778)
			(stroke
				(width 0.1524)
				(type default)
			)
			(layer "F.SilkS")
		)
		(fp_line
			(start 1.651 -1.778)
			(end -1.651 -1.778)
			(stroke
				(width 0.1524)
				(type default)
			)
			(layer "F.SilkS")
		)
		(fp_line
			(start 1.651 1.778)
			(end 1.651 -1.778)
			(stroke
				(width 0.1524)
				(type default)
			)
			(layer "F.SilkS")
		)
		(fp_poly
			(pts
				(xy -1.778 1.8796) (xy -1.778 -1.8796) (xy 1.778 -1.8796) (xy 1.778 1.8796)
			)
			(stroke
				(width 0)
				(type default)
			)
			(fill no)
			(layer "F.CrtYd")
		)
		(fp_poly
			(pts
				(xy -1.778 1.8796) (xy -1.778 -1.8796) (xy 1.778 -1.8796) (xy 1.778 1.8796)
			)
			(stroke
				(width 0)
				(type default)
			)
			(fill no)
			(layer "F.Fab")
		)
		(pad "D" smd custom
			(at 0 -0.9525)
			(size 0.1905 0.1905)
			(layers "F.Cu" "F.Mask" "F.Paste")
			(net "ATTN_LED_DR9_MOS_N")
			(options
				(clearance outline)
				(anchor circle)
			)
			(primitives
				(gr_poly
					(pts
						(arc
							(start -0.1778 0.5715)
							(mid -0.321484 0.511984)
							(end -0.381 0.3683)
						)
						(arc
							(start -0.381 -0.3683)
							(mid -0.321484 -0.511984)
							(end -0.1778 -0.5715)
						)
						(arc
							(start 0.1778 -0.5715)
							(mid 0.321484 -0.511984)
							(end 0.381 -0.3683)
						)
						(arc
							(start 0.381 0.3683)
							(mid 0.321484 0.511984)
							(end 0.1778 0.5715)
						)
					)
					(width 0)
					(fill yes)
				)
			)
		)
		(pad "G" smd custom
			(at -0.98425 0.9525)
			(size 0.1905 0.1905)
			(layers "F.Cu" "F.Mask" "F.Paste")
			(net "SSD9_CLK0_OE_MOS_N")
			(options
				(clearance outline)
				(anchor circle)
			)
			(primitives
				(gr_poly
					(pts
						(arc
							(start -0.1778 0.5715)
							(mid -0.321484 0.511984)
							(end -0.381 0.3683)
						)
						(arc
							(start -0.381 -0.3683)
							(mid -0.321484 -0.511984)
							(end -0.1778 -0.5715)
						)
						(arc
							(start 0.1778 -0.5715)
							(mid 0.321484 -0.511984)
							(end 0.381 -0.3683)
						)
						(arc
							(start 0.381 0.3683)
							(mid 0.321484 0.511984)
							(end 0.1778 0.5715)
						)
					)
					(width 0)
					(fill yes)
				)
			)
		)
		(pad "S" smd custom
			(at 0.98425 0.9525)
			(size 0.1905 0.1905)
			(layers "F.Cu" "F.Mask" "F.Paste")
			(net "ATTN_LED_DR9_R")
			(options
				(clearance outline)
				(anchor circle)
			)
			(primitives
				(gr_poly
					(pts
						(arc
							(start -0.1778 0.5715)
							(mid -0.321484 0.511984)
							(end -0.381 0.3683)
						)
						(arc
							(start -0.381 -0.3683)
							(mid -0.321484 -0.511984)
							(end -0.1778 -0.5715)
						)
						(arc
							(start 0.1778 -0.5715)
							(mid 0.321484 -0.511984)
							(end 0.381 -0.3683)
						)
						(arc
							(start 0.381 0.3683)
							(mid 0.321484 0.511984)
							(end 0.1778 0.5715)
						)
					)
					(width 0)
					(fill yes)
				)
			)
		)
	)
	(footprint ""
		(layer "F.Cu")
		(at 9.4742 -498.4242 180)
		(property "Reference" "R9508"
			(at 0 0 180)
			(layer "F.SilkS")
			(hide yes)
			(effects
				(font
					(size 1.27 1.27)
				)
			)
		)
		(property "Value" "4K7R2J-2-GP"
			(at 0.064008 -3.993896 180)
			(unlocked yes)
			(layer "F.Fab")
			(hide yes)
			(effects
				(font
					(size 1.016 1.016)
					(thickness 0.1524)
				)
			)
		)
		(property "Device Type" "R402H16"
			(at 0.064008 -5.517896 180)
			(unlocked yes)
			(layer "F.Fab")
			(hide yes)
			(effects
				(font
					(size 1.016 1.016)
					(thickness 0.1524)
				)
			)
		)
		(duplicate_pad_numbers_are_jumpers no)
		(fp_line
			(start 0.508 -0.9398)
			(end -0.508 -0.9398)
			(stroke
				(width 0.1524)
				(type default)
			)
			(layer "F.SilkS")
		)
		(fp_line
			(start -0.508 -0.9398)
			(end -0.508 0.9398)
			(stroke
				(width 0.1524)
				(type default)
			)
			(layer "F.SilkS")
		)
		(fp_rect
			(start -0.508 0.9398)
			(end 0.508 -0.9398)
			(stroke
				(width 0)
				(type default)
			)
			(fill no)
			(layer "F.CrtYd")
		)
		(fp_rect
			(start -0.508 0.9398)
			(end 0.508 -0.9398)
			(stroke
				(width 0)
				(type default)
			)
			(fill no)
			(layer "F.Fab")
		)
		(pad "1" smd custom
			(at 0 -0.4445 180)
			(size 0.1397 0.1397)
			(layers "F.Cu" "F.Mask" "F.Paste")
			(net "P3V3")
			(options
				(clearance outline)
				(anchor circle)
			)
			(primitives
				(gr_poly
					(pts
						(arc
							(start -0.1778 -0.2794)
							(mid -0.249642 -0.249642)
							(end -0.2794 -0.1778)
						)
						(arc
							(start -0.2794 0.1778)
							(mid -0.249642 0.249642)
							(end -0.1778 0.2794)
						)
						(arc
							(start 0.1778 0.2794)
							(mid 0.249642 0.249642)
							(end 0.2794 0.1778)
						)
						(arc
							(start 0.2794 -0.1778)
							(mid 0.249642 -0.249642)
							(end 0.1778 -0.2794)
						)
					)
					(width 0)
					(fill yes)
				)
			)
		)
		(pad "2" smd custom
			(at 0 0.4445 180)
			(size 0.1397 0.1397)
			(layers "F.Cu" "F.Mask" "F.Paste")
			(net "SSD5_PWREN")
			(options
				(clearance outline)
				(anchor circle)
			)
			(primitives
				(gr_poly
					(pts
						(arc
							(start -0.1778 -0.2794)
							(mid -0.249642 -0.249642)
							(end -0.2794 -0.1778)
						)
						(arc
							(start -0.2794 0.1778)
							(mid -0.249642 0.249642)
							(end -0.1778 0.2794)
						)
						(arc
							(start 0.1778 0.2794)
							(mid 0.249642 0.249642)
							(end 0.2794 0.1778)
						)
						(arc
							(start 0.2794 -0.1778)
							(mid 0.249642 -0.249642)
							(end 0.1778 -0.2794)
						)
					)
					(width 0)
					(fill yes)
				)
			)
		)
	)
	(footprint ""
		(layer "F.Cu")
		(at 232.791 -438.023 180)
		(property "Reference" "PG3"
			(at 0 0 180)
			(layer "F.SilkS")
			(hide yes)
			(effects
				(font
					(size 1.27 1.27)
				)
			)
		)
		(property "Value" "COPPER-CLOSE-GP-U"
			(at 0.0762 -2.8702 180)
			(unlocked yes)
			(layer "F.Fab")
			(hide yes)
			(effects
				(font
					(size 1.016 1.016)
					(thickness 0.1524)
				)
			)
		)
		(property "Device Type" "CON2C-U"
			(at 0.0762 -4.3942 180)
			(unlocked yes)
			(layer "F.Fab")
			(hide yes)
			(effects
				(font
					(size 1.016 1.016)
					(thickness 0.1524)
				)
			)
		)
		(duplicate_pad_numbers_are_jumpers no)
		(fp_rect
			(start -0.9398 0.9652)
			(end 0.9398 -0.9652)
			(stroke
				(width 0)
				(type default)
			)
			(fill no)
			(layer "F.CrtYd")
		)
		(fp_rect
			(start -0.9398 0.9652)
			(end 0.9398 -0.9652)
			(stroke
				(width 0)
				(type default)
			)
			(fill no)
			(layer "F.Fab")
		)
		(pad "1" smd custom
			(at 0 -0.5334 180)
			(size 0.17145 0.17145)
			(layers "F.Cu" "F.Mask" "F.Paste")
			(net "AGND_P3V3")
			(options
				(clearance outline)
				(anchor circle)
			)
			(primitives
				(gr_poly
					(pts
						(xy -0.127 0.3429) (xy -0.127 0.1651) (xy -0.635 -0.3429) (xy 0.635 -0.3429) (xy 0.127 0.1651)
						(xy 0.127 0.3429)
					)
					(width 0)
					(fill yes)
				)
			)
		)
		(pad "2" smd custom
			(at 0 0.5334 180)
			(size 0.17145 0.17145)
			(layers "F.Cu" "F.Mask" "F.Paste")
			(net "GND")
			(options
				(clearance outline)
				(anchor circle)
			)
			(primitives
				(gr_poly
					(pts
						(xy -0.635 0.3429) (xy -0.127 -0.1651) (xy -0.127 -0.3429) (xy 0.127 -0.3429) (xy 0.127 -0.1651)
						(xy 0.635 0.3429)
					)
					(width 0)
					(fill yes)
				)
			)
		)
	)
	(footprint ""
		(layer "F.Cu")
		(at 209.804 -397.637 -90)
		(property "Reference" "R138"
			(at 0 0 270)
			(layer "F.SilkS")
			(hide yes)
			(effects
				(font
					(size 1.27 1.27)
				)
			)
		)
		(property "Value" "4K7R2J-2-GP"
			(at 0.064008 -3.993896 270)
			(unlocked yes)
			(layer "F.Fab")
			(hide yes)
			(effects
				(font
					(size 1.016 1.016)
					(thickness 0.1524)
				)
			)
		)
		(property "Device Type" "R402H16"
			(at 0.064008 -5.517896 270)
			(unlocked yes)
			(layer "F.Fab")
			(hide yes)
			(effects
				(font
					(size 1.016 1.016)
					(thickness 0.1524)
				)
			)
		)
		(duplicate_pad_numbers_are_jumpers no)
		(fp_line
			(start -0.508 -0.9398)
			(end -0.508 0.9398)
			(stroke
				(width 0.1524)
				(type default)
			)
			(layer "F.SilkS")
		)
		(fp_line
			(start 0.508 -0.9398)
			(end -0.508 -0.9398)
			(stroke
				(width 0.1524)
				(type default)
			)
			(layer "F.SilkS")
		)
		(fp_rect
			(start -0.508 0.9398)
			(end 0.508 -0.9398)
			(stroke
				(width 0)
				(type default)
			)
			(fill no)
			(layer "F.CrtYd")
		)
		(fp_rect
			(start -0.508 0.9398)
			(end 0.508 -0.9398)
			(stroke
				(width 0)
				(type default)
			)
			(fill no)
			(layer "F.Fab")
		)
		(pad "1" smd custom
			(at 0 -0.4445 270)
			(size 0.1397 0.1397)
			(layers "F.Cu" "F.Mask" "F.Paste")
			(net "P12V")
			(options
				(clearance outline)
				(anchor circle)
			)
			(primitives
				(gr_poly
					(pts
						(arc
							(start -0.1778 -0.2794)
							(mid -0.249642 -0.249642)
							(end -0.2794 -0.1778)
						)
						(arc
							(start -0.2794 0.1778)
							(mid -0.249642 0.249642)
							(end -0.1778 0.2794)
						)
						(arc
							(start 0.1778 0.2794)
							(mid 0.249642 0.249642)
							(end 0.2794 0.1778)
						)
						(arc
							(start 0.2794 -0.1778)
							(mid 0.249642 -0.249642)
							(end 0.1778 -0.2794)
						)
					)
					(width 0)
					(fill yes)
				)
			)
		)
		(pad "2" smd custom
			(at 0 0.4445 270)
			(size 0.1397 0.1397)
			(layers "F.Cu" "F.Mask" "F.Paste")
			(net "SW_SSD1_R")
			(options
				(clearance outline)
				(anchor circle)
			)
			(primitives
				(gr_poly
					(pts
						(arc
							(start -0.1778 -0.2794)
							(mid -0.249642 -0.249642)
							(end -0.2794 -0.1778)
						)
						(arc
							(start -0.2794 0.1778)
							(mid -0.249642 0.249642)
							(end -0.1778 0.2794)
						)
						(arc
							(start 0.1778 0.2794)
							(mid 0.249642 0.249642)
							(end 0.2794 0.1778)
						)
						(arc
							(start 0.2794 -0.1778)
							(mid 0.249642 -0.249642)
							(end 0.1778 -0.2794)
						)
					)
					(width 0)
					(fill yes)
				)
			)
		)
	)
	(footprint ""
		(layer "F.Cu")
		(at 79.248 -435.7878 -90)
		(property "Reference" "C8897"
			(at 0 0 270)
			(layer "F.SilkS")
			(hide yes)
			(effects
				(font
					(size 1.27 1.27)
				)
			)
		)
		(property "Value" "SC10U25V3MX-GP"
			(at 0 -2.8194 270)
			(unlocked yes)
			(layer "F.Fab")
			(hide yes)
			(effects
				(font
					(size 1.016 1.016)
					(thickness 0.1524)
				)
			)
		)
		(property "Device Type" "C603H40"
			(at 0 -4.3434 270)
			(unlocked yes)
			(layer "F.Fab")
			(hide yes)
			(effects
				(font
					(size 1.016 1.016)
					(thickness 0.1524)
				)
			)
		)
		(duplicate_pad_numbers_are_jumpers no)
		(fp_line
			(start 0.508 0)
			(end -0.508 0)
			(stroke
				(width 0.2032)
				(type default)
			)
			(layer "F.SilkS")
		)
		(fp_rect
			(start -0.5842 1.3335)
			(end 0.5842 -1.3335)
			(stroke
				(width 0)
				(type default)
			)
			(fill no)
			(layer "F.CrtYd")
		)
		(fp_rect
			(start -0.5842 1.3335)
			(end 0.5842 -1.3335)
			(stroke
				(width 0)
				(type default)
			)
			(fill no)
			(layer "F.Fab")
		)
		(pad "1" smd custom
			(at 0 -0.762 270)
			(size 0.2159 0.2159)
			(layers "F.Cu" "F.Mask" "F.Paste")
			(net "VDD_DIFF_1")
			(options
				(clearance outline)
				(anchor circle)
			)
			(primitives
				(gr_poly
					(pts
						(arc
							(start -0.3302 -0.4318)
							(mid -0.402042 -0.402042)
							(end -0.4318 -0.3302)
						)
						(arc
							(start -0.4318 0.3302)
							(mid -0.402042 0.402042)
							(end -0.3302 0.4318)
						)
						(arc
							(start 0.3302 0.4318)
							(mid 0.402042 0.402042)
							(end 0.4318 0.3302)
						)
						(arc
							(start 0.4318 -0.3302)
							(mid 0.402042 -0.402042)
							(end 0.3302 -0.4318)
						)
					)
					(width 0)
					(fill yes)
				)
			)
		)
		(pad "2" smd custom
			(at 0 0.762 270)
			(size 0.2159 0.2159)
			(layers "F.Cu" "F.Mask" "F.Paste")
			(net "GND")
			(options
				(clearance outline)
				(anchor circle)
			)
			(primitives
				(gr_poly
					(pts
						(arc
							(start -0.3302 -0.4318)
							(mid -0.402042 -0.402042)
							(end -0.4318 -0.3302)
						)
						(arc
							(start -0.4318 0.3302)
							(mid -0.402042 0.402042)
							(end -0.3302 0.4318)
						)
						(arc
							(start 0.3302 0.4318)
							(mid 0.402042 0.402042)
							(end 0.4318 0.3302)
						)
						(arc
							(start 0.4318 -0.3302)
							(mid 0.402042 -0.402042)
							(end 0.3302 -0.4318)
						)
					)
					(width 0)
					(fill yes)
				)
			)
		)
	)
	(footprint ""
		(layer "F.Cu")
		(at 217.17 -431.673 180)
		(property "Reference" "PC1273"
			(at 0 0 180)
			(layer "F.SilkS")
			(hide yes)
			(effects
				(font
					(size 1.27 1.27)
				)
			)
		)
		(property "Value" "SCD1U50V3KX-GP"
			(at 0 -2.8194 180)
			(unlocked yes)
			(layer "F.Fab")
			(hide yes)
			(effects
				(font
					(size 1.016 1.016)
					(thickness 0.1524)
				)
			)
		)
		(property "Device Type" "C603H36"
			(at 0 -4.3434 180)
			(unlocked yes)
			(layer "F.Fab")
			(hide yes)
			(effects
				(font
					(size 1.016 1.016)
					(thickness 0.1524)
				)
			)
		)
		(duplicate_pad_numbers_are_jumpers no)
		(fp_line
			(start 0.508 0)
			(end -0.508 0)
			(stroke
				(width 0.2032)
				(type default)
			)
			(layer "F.SilkS")
		)
		(fp_rect
			(start -0.5842 1.3335)
			(end 0.5842 -1.3335)
			(stroke
				(width 0)
				(type default)
			)
			(fill no)
			(layer "F.CrtYd")
		)
		(fp_rect
			(start -0.5842 1.3335)
			(end 0.5842 -1.3335)
			(stroke
				(width 0)
				(type default)
			)
			(fill no)
			(layer "F.Fab")
		)
		(pad "1" smd custom
			(at 0 -0.762 180)
			(size 0.2159 0.2159)
			(layers "F.Cu" "F.Mask" "F.Paste")
			(net "P3V3_VFB_R")
			(options
				(clearance outline)
				(anchor circle)
			)
			(primitives
				(gr_poly
					(pts
						(arc
							(start -0.3302 -0.4318)
							(mid -0.402042 -0.402042)
							(end -0.4318 -0.3302)
						)
						(arc
							(start -0.4318 0.3302)
							(mid -0.402042 0.402042)
							(end -0.3302 0.4318)
						)
						(arc
							(start 0.3302 0.4318)
							(mid 0.402042 0.402042)
							(end 0.4318 0.3302)
						)
						(arc
							(start 0.4318 -0.3302)
							(mid 0.402042 -0.402042)
							(end 0.3302 -0.4318)
						)
					)
					(width 0)
					(fill yes)
				)
			)
		)
		(pad "2" smd custom
			(at 0 0.762 180)
			(size 0.2159 0.2159)
			(layers "F.Cu" "F.Mask" "F.Paste")
			(net "P3V3_OUT")
			(options
				(clearance outline)
				(anchor circle)
			)
			(primitives
				(gr_poly
					(pts
						(arc
							(start -0.3302 -0.4318)
							(mid -0.402042 -0.402042)
							(end -0.4318 -0.3302)
						)
						(arc
							(start -0.4318 0.3302)
							(mid -0.402042 0.402042)
							(end -0.3302 0.4318)
						)
						(arc
							(start 0.3302 0.4318)
							(mid 0.402042 0.402042)
							(end 0.4318 0.3302)
						)
						(arc
							(start 0.4318 -0.3302)
							(mid 0.402042 -0.402042)
							(end 0.3302 -0.4318)
						)
					)
					(width 0)
					(fill yes)
				)
			)
		)
	)
	(footprint ""
		(layer "F.Cu")
		(at 88.138 -224.282)
		(property "Reference" "R9612"
			(at 0 0 0)
			(layer "F.SilkS")
			(hide yes)
			(effects
				(font
					(size 1.27 1.27)
				)
			)
		)
		(property "Value" "10R2F-L-GP"
			(at 0.064008 -3.993896 0)
			(unlocked yes)
			(layer "F.Fab")
			(hide yes)
			(effects
				(font
					(size 1.016 1.016)
					(thickness 0.1524)
				)
			)
		)
		(property "Device Type" "R402H14"
			(at 0.064008 -5.517896 0)
			(unlocked yes)
			(layer "F.Fab")
			(hide yes)
			(effects
				(font
					(size 1.016 1.016)
					(thickness 0.1524)
				)
			)
		)
		(duplicate_pad_numbers_are_jumpers no)
		(fp_line
			(start -0.508 -0.9398)
			(end -0.508 0.9398)
			(stroke
				(width 0.1524)
				(type default)
			)
			(layer "F.SilkS")
		)
		(fp_line
			(start 0.508 -0.9398)
			(end -0.508 -0.9398)
			(stroke
				(width 0.1524)
				(type default)
			)
			(layer "F.SilkS")
		)
		(fp_rect
			(start -0.508 0.9398)
			(end 0.508 -0.9398)
			(stroke
				(width 0)
				(type default)
			)
			(fill no)
			(layer "F.CrtYd")
		)
		(fp_rect
			(start -0.508 0.9398)
			(end 0.508 -0.9398)
			(stroke
				(width 0)
				(type default)
			)
			(fill no)
			(layer "F.Fab")
		)
		(pad "1" smd custom
			(at 0 -0.4445)
			(size 0.1397 0.1397)
			(layers "F.Cu" "F.Mask" "F.Paste")
			(net "SSD12_CLK0_OE_N")
			(options
				(clearance outline)
				(anchor circle)
			)
			(primitives
				(gr_poly
					(pts
						(arc
							(start -0.1778 -0.2794)
							(mid -0.249642 -0.249642)
							(end -0.2794 -0.1778)
						)
						(arc
							(start -0.2794 0.1778)
							(mid -0.249642 0.249642)
							(end -0.1778 0.2794)
						)
						(arc
							(start 0.1778 0.2794)
							(mid 0.249642 0.249642)
							(end 0.2794 0.1778)
						)
						(arc
							(start 0.2794 -0.1778)
							(mid 0.249642 -0.249642)
							(end 0.1778 -0.2794)
						)
					)
					(width 0)
					(fill yes)
				)
			)
		)
		(pad "2" smd custom
			(at 0 0.4445)
			(size 0.1397 0.1397)
			(layers "F.Cu" "F.Mask" "F.Paste")
			(net "SSD12_CLK0_OE_R_N")
			(options
				(clearance outline)
				(anchor circle)
			)
			(primitives
				(gr_poly
					(pts
						(arc
							(start -0.1778 -0.2794)
							(mid -0.249642 -0.249642)
							(end -0.2794 -0.1778)
						)
						(arc
							(start -0.2794 0.1778)
							(mid -0.249642 0.249642)
							(end -0.1778 0.2794)
						)
						(arc
							(start 0.1778 0.2794)
							(mid 0.249642 0.249642)
							(end 0.2794 0.1778)
						)
						(arc
							(start 0.2794 -0.1778)
							(mid 0.249642 -0.249642)
							(end 0.1778 -0.2794)
						)
					)
					(width 0)
					(fill yes)
				)
			)
		)
	)
)
